# T6G (Grand Teton) — schematic netlist excerpt (pin names and nets, part order shuffled) for the footprints in the layout excerpt that follows; sources: Cadence DE-HDL packaged netlist, KiCad conversion of 04192023_DAF0TMB3IC0_F0TG_MB_C_brd_V02_OCP.brd

PR6520  Q_RES  0 5% CHIP  pkg 0402LF  page 361 : A = GND ; B = P1V8_RETIMER_CPU1_MODE
PC387  Q_CAPP  220UF 4V 20% SPCAP  pkg SMLF  page 218 : A = PVDDCR_CPU1_P1 ; B = GND

(kicad_pcb
	(version 20260206)
	(generator "pcbnew")
	(generator_version "10.0")
	(general
		(thickness 1.6)
		(legacy_teardrops no)
	)
	(paper "A4")
	(title_block
		(title "04192023_DAF0TMB3IC0_F0TG_MB_C_brd_V02_OCP.brd")
		(comment 1 "Grand Teton / footprints 6013-6014 of 8354")
	)
	(layers
		(0 "F.Cu" signal "TOP")
		(4 "In1.Cu" signal "GND")
		(6 "In2.Cu" signal "IN1")
		(8 "In3.Cu" signal "GND1")
		(10 "In4.Cu" signal "IN2")
		(12 "In5.Cu" signal "GND2")
		(14 "In6.Cu" signal "IN3")
		(16 "In7.Cu" signal "GND3")
		(18 "In8.Cu" signal "VCC")
		(20 "In9.Cu" signal "VCC1")
		(22 "In10.Cu" signal "GND4")
		(24 "In11.Cu" signal "IN4")
		(26 "In12.Cu" signal "GND5")
		(28 "In13.Cu" signal "IN5")
		(30 "In14.Cu" signal "GND6")
		(32 "In15.Cu" signal "IN6")
		(34 "In16.Cu" signal "GND7")
		(2 "B.Cu" signal "BOTTOM")
		(9 "F.Adhes" user "F.Adhesive")
		(11 "B.Adhes" user "B.Adhesive")
		(13 "F.Paste" user "Package Geometry/Pastemask Top")
		(15 "B.Paste" user "Package Geometry/Pastemask Bottom")
		(5 "F.SilkS" user "Ref Des/Silkscreen Top")
		(7 "B.SilkS" user "Ref Des/Silkscreen Bottom")
		(1 "F.Mask" user "Board Geometry/Soldermask Top")
		(3 "B.Mask" user "Board Geometry/Soldermask Bottom")
		(17 "Dwgs.User" user "User.Drawings")
		(19 "Cmts.User" user "User.Comments")
		(21 "Eco1.User" user "User.Eco1")
		(23 "Eco2.User" user "User.Eco2")
		(25 "Edge.Cuts" user "Board Geometry/Outline")
		(27 "Margin" user)
		(31 "F.CrtYd" user "Package Geometry/Place Bound Top")
		(29 "B.CrtYd" user "Package Geometry/Place Bound Bottom")
		(35 "F.Fab" user "Ref Des/Assembly Top")
		(33 "B.Fab" user "Ref Des/Assembly Bottom")
	)
	(footprint ""
		(layer "B.Cu")
		(at 70.500494 -328.24547 -90)
		(property "Reference" "PC387"
			(at 10.257536 -0.312166 270)
			(unlocked yes)
			(layer "B.SilkS")
			(effects
				(font
					(size 0.7874 0.5842)
					(thickness 0.1524)
				)
				(justify left mirror)
			)
		)
		(property "Value" ""
			(at 0 0 90)
			(layer "B.Fab")
			(effects
				(font
					(size 1.27 1.27)
				)
				(justify mirror)
			)
		)
		(duplicate_pad_numbers_are_jumpers no)
		(fp_line
			(start -4.533392 2.249932)
			(end 4.533392 2.249932)
			(stroke
				(width 0.1524)
				(type default)
			)
			(layer "B.SilkS")
		)
		(fp_line
			(start 4.533392 2.249932)
			(end 4.533392 -2.249932)
			(stroke
				(width 0.1524)
				(type default)
			)
			(layer "B.SilkS")
		)
		(fp_line
			(start -4.533392 -2.249932)
			(end -4.533392 2.249932)
			(stroke
				(width 0.1524)
				(type default)
			)
			(layer "B.SilkS")
		)
		(fp_line
			(start 4.533392 -2.249932)
			(end -4.533392 -2.249932)
			(stroke
				(width 0.1524)
				(type default)
			)
			(layer "B.SilkS")
		)
		(fp_rect
			(start 5.39242 2.326132)
			(end 4.533392 -2.326132)
			(stroke
				(width 0)
				(type default)
			)
			(fill yes)
			(layer "B.SilkS")
		)
		(fp_line
			(start -3.750056 2.249932)
			(end 3.750056 2.249932)
			(stroke
				(width 0.1)
				(type default)
			)
			(layer "B.Fab")
		)
		(fp_line
			(start 3.750056 2.249932)
			(end 3.750056 -2.249932)
			(stroke
				(width 0.1)
				(type default)
			)
			(layer "B.Fab")
		)
		(fp_line
			(start -3.750056 -2.249932)
			(end -3.750056 2.249932)
			(stroke
				(width 0.1)
				(type default)
			)
			(layer "B.Fab")
		)
		(fp_line
			(start 3.750056 -2.249932)
			(end -3.750056 -2.249932)
			(stroke
				(width 0.1)
				(type default)
			)
			(layer "B.Fab")
		)
		(fp_text user "-"
			(at -4.489196 2.477516 270)
			(unlocked yes)
			(layer "B.SilkS")
			(effects
				(font
					(size 1.905 1.4224)
					(thickness 0.1524)
				)
				(justify left mirror)
			)
		)
		(fp_text user "+"
			(at 6.322314 0.786384 180)
			(unlocked yes)
			(layer "B.SilkS")
			(effects
				(font
					(size 1.905 1.4224)
					(thickness 0.1524)
				)
				(justify left mirror)
			)
		)
		(fp_text user "+"
			(at 6.322314 0.786384 180)
			(unlocked yes)
			(layer "B.Fab")
			(effects
				(font
					(size 1.905 1.4224)
					(thickness 0.1524)
				)
				(justify left mirror)
			)
		)
		(fp_text user "-"
			(at -4.8514 -0.14605 270)
			(unlocked yes)
			(layer "B.Fab")
			(effects
				(font
					(size 1.905 1.4224)
					(thickness 0.1524)
				)
				(justify left mirror)
			)
		)
		(pad "1" smd rect
			(at 3.199892 0 90)
			(size 2.413 2.8194)
			(layers "B.Cu" "B.Mask" "B.Paste")
			(net "PVDDCR_CPU1_P1")
		)
		(pad "2" smd rect
			(at -3.199892 0 90)
			(size 2.413 2.8194)
			(layers "B.Cu" "B.Mask" "B.Paste")
			(net "GND")
		)
	)
	(footprint ""
		(layer "B.Cu")
		(at 228.383592 -290.564062)
		(property "Reference" "PR6520"
			(at 0 0 0)
			(layer "B.SilkS")
			(hide yes)
			(effects
				(font
					(size 1.27 1.27)
				)
				(justify mirror)
			)
		)
		(property "Value" ""
			(at 0 0 0)
			(layer "B.Fab")
			(effects
				(font
					(size 1.27 1.27)
				)
				(justify mirror)
			)
		)
		(duplicate_pad_numbers_are_jumpers no)
		(fp_line
			(start -0.7874 -0.4064)
			(end -0.7874 0.4064)
			(stroke
				(width 0.1524)
				(type default)
			)
			(layer "B.SilkS")
		)
		(fp_line
			(start -0.7874 0.4064)
			(end 0.7874 0.4064)
			(stroke
				(width 0.1524)
				(type default)
			)
			(layer "B.SilkS")
		)
		(fp_line
			(start 0.7874 -0.4064)
			(end -0.7874 -0.4064)
			(stroke
				(width 0.1524)
				(type default)
			)
			(layer "B.SilkS")
		)
		(fp_line
			(start 0.7874 0.4064)
			(end 0.7874 -0.4064)
			(stroke
				(width 0.1524)
				(type default)
			)
			(layer "B.SilkS")
		)
		(fp_line
			(start -0.67945 -0.3048)
			(end -0.67945 0.3048)
			(stroke
				(width 0.1)
				(type default)
			)
			(layer "B.Fab")
		)
		(fp_line
			(start -0.67945 0.3048)
			(end -0.120396 0.3048)
			(stroke
				(width 0.1)
				(type default)
			)
			(layer "B.Fab")
		)
		(fp_line
			(start -0.12065 -0.3048)
			(end -0.67945 -0.3048)
			(stroke
				(width 0.1)
				(type default)
			)
			(layer "B.Fab")
		)
		(fp_line
			(start -0.12065 -0.2794)
			(end -0.12065 -0.3048)
			(stroke
				(width 0.1)
				(type default)
			)
			(layer "B.Fab")
		)
		(fp_line
			(start -0.120396 0.2794)
			(end 0.12065 0.2794)
			(stroke
				(width 0.1)
				(type default)
			)
			(layer "B.Fab")
		)
		(fp_line
			(start -0.120396 0.3048)
			(end -0.120396 0.2794)
			(stroke
				(width 0.1)
				(type default)
			)
			(layer "B.Fab")
		)
		(fp_line
			(start 0.12065 -0.305054)
			(end 0.12065 -0.2794)
			(stroke
				(width 0.1)
				(type default)
			)
			(layer "B.Fab")
		)
		(fp_line
			(start 0.12065 -0.2794)
			(end -0.12065 -0.2794)
			(stroke
				(width 0.1)
				(type default)
			)
			(layer "B.Fab")
		)
		(fp_line
			(start 0.12065 0.2794)
			(end 0.12065 0.3048)
			(stroke
				(width 0.1)
				(type default)
			)
			(layer "B.Fab")
		)
		(fp_line
			(start 0.12065 0.3048)
			(end 0.67945 0.3048)
			(stroke
				(width 0.1)
				(type default)
			)
			(layer "B.Fab")
		)
		(fp_line
			(start 0.67945 -0.305054)
			(end 0.12065 -0.305054)
			(stroke
				(width 0.1)
				(type default)
			)
			(layer "B.Fab")
		)
		(fp_line
			(start 0.67945 0.3048)
			(end 0.67945 -0.305054)
			(stroke
				(width 0.1)
				(type default)
			)
			(layer "B.Fab")
		)
		(pad "1" smd circle
			(at 0.40005 0 180)
			(size 0 0)
			(layers "B.Cu" "B.Mask" "B.Paste")
			(net "GND")
		)
		(pad "2" smd circle
			(at -0.40005 0 180)
			(size 0 0)
			(layers "B.Cu" "B.Mask" "B.Paste")
			(net "P1V8_RETIMER_CPU1_MODE")
		)
	)
)
